FILE_TYPE = CONNECTIVITY;
{Allegro Design Entry HDL 16.6-p007 (v16-6-112F) 10/10/2012}
"PAGE_NUMBER" = 23;
0"NC";
1"M_A_DQ<63:0>";
2"M_A_ECC<7:0>";
3"M_A_CLK_DP<3:0>";
4"M_A_CLK_DN<3:0>";
5"M_A_ODT<3:0>";
6"M_A_MA<17:0>";
7"M_A_CS_N<7:0>";
8"M_A_CKE<3:0>";
9"M_A_BG<1:0>";
10"M_A_BA<1:0>";
11"M_A_DQS_DP<17:0>";
12"M_A_DQS_DN<17:0>";
13"M_A_DQS_DP<17>";
14"M_A_DQS_DP<16>";
15"M_A_DQS_DP<15>";
16"M_A_DQS_DP<14>";
17"M_A_DQS_DP<13>";
18"M_A_DQS_DP<12>";
19"M_A_DQS_DP<11>";
20"M_A_DQS_DP<10>";
21"M_A_DQS_DP<9>";
22"M_A_DQS_DP<8>";
23"M_A_DQS_DP<7>";
24"M_A_DQS_DP<6>";
25"M_A_DQS_DP<5>";
26"M_A_DQS_DN<17>";
27"M_A_DQS_DN<16>";
28"M_A_DQS_DN<15>";
29"M_A_DQS_DN<14>";
30"M_A_DQS_DN<13>";
31"M_A_DQS_DN<12>";
32"M_A_DQS_DN<11>";
33"M_A_DQS_DN<10>";
34"M_A_DQS_DN<9>";
35"M_A_DQS_DN<8>";
36"M_A_DQS_DN<7>";
37"M_A_DQS_DN<6>";
38"M_A_DQS_DN<5>";
39"M_A_DQS_DN<4>";
40"M_A_DQS_DN<3>";
41"M_A_DQS_DN<2>";
42"M_A_DQS_DN<1>";
43"M_A_DQS_DN<0>";
44"M_A_DQS_DP<4>";
45"M_A_DQS_DP<3>";
46"M_A_DQS_DP<2>";
47"M_A_DQS_DP<1>";
48"M_A_DQS_DP<0>";
49"M_A_MA<17>";
50"M_A_MA<16>";
51"M_A_MA<15>";
52"M_A_MA<14>";
53"M_A_MA<13>";
54"M_A_MA<12>";
55"M_A_MA<11>";
56"M_A_MA<10>";
57"M_A_MA<9>";
58"M_A_MA<8>";
59"M_A_MA<7>";
60"M_A_MA<6>";
61"M_A_MA<5>";
62"M_A_MA<4>";
63"M_A_MA<3>";
64"M_A_MA<2>";
65"M_A_ACT_N";
66"M_A_ALERT_N";
67"M_A_PAR";
68"M_A_BA<1>";
69"M_A_BA<0>";
70"M_A_BG<1>";
71"M_A_BG<0>";
72"M_A_CKE<3>";
73"M_A_CKE<2>";
74"M_A_CKE<1>";
75"M_A_CKE<0>";
76"M_A_CS_N<7>";
77"M_A_CS_N<6>";
78"M_A_CS_N<5>";
79"M_A_CS_N<4>";
80"M_A_CS_N<3>";
81"M_A_CS_N<2>";
82"M_A_CS_N<1>";
83"M_A_CS_N<0>";
84"M_A_MA<1>";
85"M_A_MA<0>";
86"M_A_ODT<3>";
87"M_A_ODT<2>";
88"M_A_ODT<1>";
89"M_A_ODT<0>";
90"M_A_DQ<63>";
91"M_A_DQ<62>";
92"M_A_DQ<61>";
93"M_A_DQ<60>";
94"M_A_DQ<59>";
95"M_A_DQ<58>";
96"M_A_DQ<57>";
97"M_A_DQ<56>";
98"M_A_DQ<55>";
99"M_A_DQ<54>";
100"M_A_DQ<53>";
101"M_A_DQ<52>";
102"M_A_DQ<51>";
103"M_A_DQ<50>";
104"M_A_DQ<49>";
105"M_A_DQ<48>";
106"M_A_DQ<47>";
107"M_A_DQ<46>";
108"M_A_DQ<45>";
109"M_A_DQ<44>";
110"M_A_DQ<43>";
111"M_A_DQ<42>";
112"M_A_DQ<41>";
113"M_A_DQ<40>";
114"M_A_DQ<39>";
115"M_A_DQ<38>";
116"M_A_DQ<37>";
117"M_A_DQ<36>";
118"M_A_DQ<35>";
119"M_A_DQ<34>";
120"M_A_DQ<33>";
121"M_A_DQ<32>";
122"M_A_DQ<31>";
123"M_A_DQ<30>";
124"M_A_DQ<29>";
125"M_A_DQ<28>";
126"M_A_DQ<27>";
127"M_A_DQ<26>";
128"M_A_DQ<25>";
129"M_A_DQ<24>";
130"M_A_DQ<23>";
131"M_A_DQ<22>";
132"M_A_DQ<21>";
133"M_A_DQ<20>";
134"M_A_DQ<19>";
135"M_A_DQ<18>";
136"M_A_DQ<17>";
137"M_A_DQ<16>";
138"M_A_DQ<15>";
139"M_A_DQ<14>";
140"M_A_DQ<13>";
141"M_A_DQ<12>";
142"M_A_DQ<11>";
143"M_A_DQ<10>";
144"M_A_CLK_DN<3>";
145"M_A_CLK_DN<2>";
146"M_A_CLK_DN<1>";
147"M_A_CLK_DN<0>";
148"M_A_CLK_DP<3>";
149"M_A_CLK_DP<2>";
150"M_A_CLK_DP<1>";
151"M_A_CLK_DP<0>";
152"M_A_DQ<9>";
153"M_A_DQ<8>";
154"M_A_DQ<7>";
155"M_A_DQ<6>";
156"M_A_DQ<5>";
157"M_A_DQ<3>";
158"M_A_DQ<2>";
159"M_A_DQ<1>";
160"M_A_DQ<0>";
161"M_A_ECC<7>";
162"M_A_ECC<6>";
163"M_A_ECC<5>";
164"M_A_ECC<4>";
165"M_A_ECC<3>";
166"M_A_ECC<2>";
167"M_A_ECC<1>";
168"M_A_ECC<0>";
169"M_A_C<2>";
170"M_A_DQ<4>";
%"TAP"
"6","(-5600,850)","0","mstr_standard","I10";
;
HDL_TAP"TRUE"
BODY_TYPE"PLUMBING"
CDS_LIB"mstr_standard";
"B \NAC \NWC"3;
"S \NAC"
BN"0"151;
%"TAP"
"6","(-2875,1600)","2","mstr_standard","I100";
;
HDL_TAP"TRUE"
BODY_TYPE"PLUMBING"
CDS_LIB"mstr_standard";
"B \NAC \NWC"5;
"S \NAC"
BN"3"86;
%"TAP"
"6","(-2875,1700)","2","mstr_standard","I101";
;
HDL_TAP"TRUE"
BODY_TYPE"PLUMBING"
CDS_LIB"mstr_standard";
"B \NAC \NWC"8;
"S \NAC"
BN"0"75;
%"TAP"
"6","(-2875,1550)","2","mstr_standard","I102";
;
HDL_TAP"TRUE"
BODY_TYPE"PLUMBING"
CDS_LIB"mstr_standard";
"B \NAC \NWC"5;
"S \NAC"
BN"2"87;
%"TAP"
"6","(-2875,1500)","2","mstr_standard","I103";
;
HDL_TAP"TRUE"
BODY_TYPE"PLUMBING"
CDS_LIB"mstr_standard";
"B \NAC \NWC"5;
"S \NAC"
BN"1"88;
%"TAP"
"6","(-2875,1850)","2","mstr_standard","I104";
;
HDL_TAP"TRUE"
BODY_TYPE"PLUMBING"
CDS_LIB"mstr_standard";
"B \NAC \NWC"8;
"S \NAC"
BN"3"72;
%"TAP"
"6","(-2875,1950)","2","mstr_standard","I105";
;
HDL_TAP"TRUE"
BODY_TYPE"PLUMBING"
CDS_LIB"mstr_standard";
"B \NAC \NWC"6;
"S \NAC"
BN"0"85;
%"TAP"
"6","(-2875,1800)","2","mstr_standard","I106";
;
HDL_TAP"TRUE"
BODY_TYPE"PLUMBING"
CDS_LIB"mstr_standard";
"B \NAC \NWC"8;
"S \NAC"
BN"2"73;
%"TAP"
"6","(-2875,1750)","2","mstr_standard","I107";
;
HDL_TAP"TRUE"
BODY_TYPE"PLUMBING"
CDS_LIB"mstr_standard";
"B \NAC \NWC"8;
"S \NAC"
BN"1"74;
%"TAP"
"6","(-2875,2000)","2","mstr_standard","I108";
;
HDL_TAP"TRUE"
BODY_TYPE"PLUMBING"
CDS_LIB"mstr_standard";
"B \NAC \NWC"6;
"S \NAC"
BN"1"84;
%"TAP"
"6","(-2875,2050)","2","mstr_standard","I109";
;
HDL_TAP"TRUE"
BODY_TYPE"PLUMBING"
CDS_LIB"mstr_standard";
"B \NAC \NWC"6;
"S \NAC"
BN"2"64;
%"TAP"
"6","(-5600,950)","0","mstr_standard","I11";
;
HDL_TAP"TRUE"
BODY_TYPE"PLUMBING"
CDS_LIB"mstr_standard";
"B \NAC \NWC"3;
"S \NAC"
BN"2"149;
%"TAP"
"6","(-2875,2100)","2","mstr_standard","I110";
;
HDL_TAP"TRUE"
BODY_TYPE"PLUMBING"
CDS_LIB"mstr_standard";
"B \NAC \NWC"6;
"S \NAC"
BN"3"63;
%"TAP"
"6","(-2875,2250)","2","mstr_standard","I111";
;
HDL_TAP"TRUE"
BODY_TYPE"PLUMBING"
CDS_LIB"mstr_standard";
"B \NAC \NWC"6;
"S \NAC"
BN"6"60;
%"TAP"
"6","(-2875,2200)","2","mstr_standard","I112";
;
HDL_TAP"TRUE"
BODY_TYPE"PLUMBING"
CDS_LIB"mstr_standard";
"B \NAC \NWC"6;
"S \NAC"
BN"5"61;
%"TAP"
"6","(-2875,2150)","2","mstr_standard","I113";
;
HDL_TAP"TRUE"
BODY_TYPE"PLUMBING"
CDS_LIB"mstr_standard";
"B \NAC \NWC"6;
"S \NAC"
BN"4"62;
%"TAP"
"6","(-2875,2400)","2","mstr_standard","I114";
;
HDL_TAP"TRUE"
BODY_TYPE"PLUMBING"
CDS_LIB"mstr_standard";
"B \NAC \NWC"6;
"S \NAC"
BN"9"57;
%"TAP"
"6","(-2875,2450)","2","mstr_standard","I115";
;
HDL_TAP"TRUE"
BODY_TYPE"PLUMBING"
CDS_LIB"mstr_standard";
"B \NAC \NWC"6;
"S \NAC"
BN"10"56;
%"TAP"
"6","(-2875,2500)","2","mstr_standard","I116";
;
HDL_TAP"TRUE"
BODY_TYPE"PLUMBING"
CDS_LIB"mstr_standard";
"B \NAC \NWC"6;
"S \NAC"
BN"11"55;
%"TAP"
"6","(-2875,2350)","2","mstr_standard","I117";
;
HDL_TAP"TRUE"
BODY_TYPE"PLUMBING"
CDS_LIB"mstr_standard";
"B \NAC \NWC"6;
"S \NAC"
BN"8"58;
%"TAP"
"6","(-2875,2300)","2","mstr_standard","I118";
;
HDL_TAP"TRUE"
BODY_TYPE"PLUMBING"
CDS_LIB"mstr_standard";
"B \NAC \NWC"6;
"S \NAC"
BN"7"59;
%"TAP"
"6","(-2875,2650)","2","mstr_standard","I119";
;
HDL_TAP"TRUE"
BODY_TYPE"PLUMBING"
CDS_LIB"mstr_standard";
"B \NAC \NWC"6;
"S \NAC"
BN"14"52;
%"TAP"
"6","(-5600,1000)","0","mstr_standard","I12";
;
HDL_TAP"TRUE"
BODY_TYPE"PLUMBING"
CDS_LIB"mstr_standard";
"B \NAC \NWC"3;
"S \NAC"
BN"3"148;
%"TAP"
"6","(-2875,2700)","2","mstr_standard","I120";
;
HDL_TAP"TRUE"
BODY_TYPE"PLUMBING"
CDS_LIB"mstr_standard";
"B \NAC \NWC"6;
"S \NAC"
BN"15"51;
%"TAP"
"6","(-2875,2750)","2","mstr_standard","I121";
;
HDL_TAP"TRUE"
BODY_TYPE"PLUMBING"
CDS_LIB"mstr_standard";
"B \NAC \NWC"6;
"S \NAC"
BN"16"50;
%"TAP"
"6","(-2875,2600)","2","mstr_standard","I122";
;
HDL_TAP"TRUE"
BODY_TYPE"PLUMBING"
CDS_LIB"mstr_standard";
"B \NAC \NWC"6;
"S \NAC"
BN"13"53;
%"TAP"
"6","(-2875,2550)","2","mstr_standard","I123";
;
HDL_TAP"TRUE"
BODY_TYPE"PLUMBING"
CDS_LIB"mstr_standard";
"B \NAC \NWC"6;
"S \NAC"
BN"12"54;
%"TAP"
"6","(-2875,2900)","2","mstr_standard","I124";
;
HDL_TAP"TRUE"
BODY_TYPE"PLUMBING"
CDS_LIB"mstr_standard";
"B \NAC \NWC"12;
"S \NAC"
BN"0"43;
%"TAP"
"6","(-2875,3000)","2","mstr_standard","I125";
;
HDL_TAP"TRUE"
BODY_TYPE"PLUMBING"
CDS_LIB"mstr_standard";
"B \NAC \NWC"12;
"S \NAC"
BN"2"41;
%"TAP"
"6","(-2875,2950)","2","mstr_standard","I126";
;
HDL_TAP"TRUE"
BODY_TYPE"PLUMBING"
CDS_LIB"mstr_standard";
"B \NAC \NWC"12;
"S \NAC"
BN"1"42;
%"TAP"
"6","(-2875,2800)","2","mstr_standard","I127";
;
HDL_TAP"TRUE"
BODY_TYPE"PLUMBING"
CDS_LIB"mstr_standard";
"B \NAC \NWC"6;
"S \NAC"
BN"17"49;
%"TAP"
"6","(-2875,3200)","2","mstr_standard","I128";
;
HDL_TAP"TRUE"
BODY_TYPE"PLUMBING"
CDS_LIB"mstr_standard";
"B \NAC \NWC"12;
"S \NAC"
BN"6"37;
%"TAP"
"6","(-2875,3250)","2","mstr_standard","I129";
;
HDL_TAP"TRUE"
BODY_TYPE"PLUMBING"
CDS_LIB"mstr_standard";
"B \NAC \NWC"12;
"S \NAC"
BN"7"36;
%"TAP"
"6","(-5600,1100)","0","mstr_standard","I13";
;
HDL_TAP"TRUE"
BODY_TYPE"PLUMBING"
CDS_LIB"mstr_standard";
"B \NAC \NWC"2;
"S \NAC"
BN"0"168;
%"TAP"
"6","(-2875,3150)","2","mstr_standard","I130";
;
HDL_TAP"TRUE"
BODY_TYPE"PLUMBING"
CDS_LIB"mstr_standard";
"B \NAC \NWC"12;
"S \NAC"
BN"5"38;
%"TAP"
"6","(-2875,3100)","2","mstr_standard","I131";
;
HDL_TAP"TRUE"
BODY_TYPE"PLUMBING"
CDS_LIB"mstr_standard";
"B \NAC \NWC"12;
"S \NAC"
BN"4"39;
%"TAP"
"6","(-2875,3050)","2","mstr_standard","I132";
;
HDL_TAP"TRUE"
BODY_TYPE"PLUMBING"
CDS_LIB"mstr_standard";
"B \NAC \NWC"12;
"S \NAC"
BN"3"40;
%"TAP"
"6","(-2875,3500)","2","mstr_standard","I133";
;
HDL_TAP"TRUE"
BODY_TYPE"PLUMBING"
CDS_LIB"mstr_standard";
"B \NAC \NWC"12;
"S \NAC"
BN"12"31;
%"TAP"
"6","(-2875,3450)","2","mstr_standard","I134";
;
HDL_TAP"TRUE"
BODY_TYPE"PLUMBING"
CDS_LIB"mstr_standard";
"B \NAC \NWC"12;
"S \NAC"
BN"11"32;
%"TAP"
"6","(-2875,3400)","2","mstr_standard","I135";
;
HDL_TAP"TRUE"
BODY_TYPE"PLUMBING"
CDS_LIB"mstr_standard";
"B \NAC \NWC"12;
"S \NAC"
BN"10"33;
%"TAP"
"6","(-2875,3350)","2","mstr_standard","I136";
;
HDL_TAP"TRUE"
BODY_TYPE"PLUMBING"
CDS_LIB"mstr_standard";
"B \NAC \NWC"12;
"S \NAC"
BN"9"34;
%"TAP"
"6","(-2875,3300)","2","mstr_standard","I137";
;
HDL_TAP"TRUE"
BODY_TYPE"PLUMBING"
CDS_LIB"mstr_standard";
"B \NAC \NWC"12;
"S \NAC"
BN"8"35;
%"TAP"
"6","(-2875,3700)","2","mstr_standard","I138";
;
HDL_TAP"TRUE"
BODY_TYPE"PLUMBING"
CDS_LIB"mstr_standard";
"B \NAC \NWC"12;
"S \NAC"
BN"16"27;
%"TAP"
"6","(-2875,3750)","2","mstr_standard","I139";
;
HDL_TAP"TRUE"
BODY_TYPE"PLUMBING"
CDS_LIB"mstr_standard";
"B \NAC \NWC"12;
"S \NAC"
BN"17"26;
%"TAP"
"6","(-5600,1150)","0","mstr_standard","I14";
;
HDL_TAP"TRUE"
BODY_TYPE"PLUMBING"
CDS_LIB"mstr_standard";
"B \NAC \NWC"2;
"S \NAC"
BN"1"167;
%"TAP"
"6","(-2875,3650)","2","mstr_standard","I140";
;
HDL_TAP"TRUE"
BODY_TYPE"PLUMBING"
CDS_LIB"mstr_standard";
"B \NAC \NWC"12;
"S \NAC"
BN"15"28;
%"TAP"
"6","(-2875,3600)","2","mstr_standard","I141";
;
HDL_TAP"TRUE"
BODY_TYPE"PLUMBING"
CDS_LIB"mstr_standard";
"B \NAC \NWC"12;
"S \NAC"
BN"14"29;
%"TAP"
"6","(-2875,3550)","2","mstr_standard","I142";
;
HDL_TAP"TRUE"
BODY_TYPE"PLUMBING"
CDS_LIB"mstr_standard";
"B \NAC \NWC"12;
"S \NAC"
BN"13"30;
%"TAP"
"6","(-2875,3950)","2","mstr_standard","I143";
;
HDL_TAP"TRUE"
BODY_TYPE"PLUMBING"
CDS_LIB"mstr_standard";
"B \NAC \NWC"11;
"S \NAC"
BN"2"46;
%"TAP"
"6","(-2875,4000)","2","mstr_standard","I144";
;
HDL_TAP"TRUE"
BODY_TYPE"PLUMBING"
CDS_LIB"mstr_standard";
"B \NAC \NWC"11;
"S \NAC"
BN"3"45;
%"TAP"
"6","(-2875,3900)","2","mstr_standard","I145";
;
HDL_TAP"TRUE"
BODY_TYPE"PLUMBING"
CDS_LIB"mstr_standard";
"B \NAC \NWC"11;
"S \NAC"
BN"1"47;
%"TAP"
"6","(-2875,3850)","2","mstr_standard","I146";
;
HDL_TAP"TRUE"
BODY_TYPE"PLUMBING"
CDS_LIB"mstr_standard";
"B \NAC \NWC"11;
"S \NAC"
BN"0"48;
%"TAP"
"6","(-5600,1200)","0","mstr_standard","I15";
;
HDL_TAP"TRUE"
BODY_TYPE"PLUMBING"
CDS_LIB"mstr_standard";
"B \NAC \NWC"2;
"S \NAC"
BN"2"166;
%"TAP"
"6","(-2875,4050)","2","mstr_standard","I157";
;
HDL_TAP"TRUE"
BODY_TYPE"PLUMBING"
CDS_LIB"mstr_standard";
"B \NAC \NWC"11;
"S \NAC"
BN"4"44;
%"TAP"
"6","(-2875,4100)","2","mstr_standard","I158";
;
HDL_TAP"TRUE"
BODY_TYPE"PLUMBING"
CDS_LIB"mstr_standard";
"B \NAC \NWC"11;
"S \NAC"
BN"5"25;
%"TAP"
"6","(-2875,4150)","2","mstr_standard","I159";
;
HDL_TAP"TRUE"
BODY_TYPE"PLUMBING"
CDS_LIB"mstr_standard";
"B \NAC \NWC"11;
"S \NAC"
BN"6"24;
%"TAP"
"6","(-5600,1300)","0","mstr_standard","I16";
;
HDL_TAP"TRUE"
BODY_TYPE"PLUMBING"
CDS_LIB"mstr_standard";
"B \NAC \NWC"2;
"S \NAC"
BN"4"164;
%"TAP"
"6","(-2875,4300)","2","mstr_standard","I160";
;
HDL_TAP"TRUE"
BODY_TYPE"PLUMBING"
CDS_LIB"mstr_standard";
"B \NAC \NWC"11;
"S \NAC"
BN"9"21;
%"TAP"
"6","(-2875,4250)","2","mstr_standard","I161";
;
HDL_TAP"TRUE"
BODY_TYPE"PLUMBING"
CDS_LIB"mstr_standard";
"B \NAC \NWC"11;
"S \NAC"
BN"8"22;
%"TAP"
"6","(-2875,4200)","2","mstr_standard","I162";
;
HDL_TAP"TRUE"
BODY_TYPE"PLUMBING"
CDS_LIB"mstr_standard";
"B \NAC \NWC"11;
"S \NAC"
BN"7"23;
%"TAP"
"6","(-2875,4450)","2","mstr_standard","I163";
;
HDL_TAP"TRUE"
BODY_TYPE"PLUMBING"
CDS_LIB"mstr_standard";
"B \NAC \NWC"11;
"S \NAC"
BN"12"18;
%"TAP"
"6","(-2875,4500)","2","mstr_standard","I164";
;
HDL_TAP"TRUE"
BODY_TYPE"PLUMBING"
CDS_LIB"mstr_standard";
"B \NAC \NWC"11;
"S \NAC"
BN"13"17;
%"TAP"
"6","(-2875,4550)","2","mstr_standard","I165";
;
HDL_TAP"TRUE"
BODY_TYPE"PLUMBING"
CDS_LIB"mstr_standard";
"B \NAC \NWC"11;
"S \NAC"
BN"14"16;
%"TAP"
"6","(-2875,4400)","2","mstr_standard","I166";
;
HDL_TAP"TRUE"
BODY_TYPE"PLUMBING"
CDS_LIB"mstr_standard";
"B \NAC \NWC"11;
"S \NAC"
BN"11"19;
%"TAP"
"6","(-2875,4350)","2","mstr_standard","I167";
;
HDL_TAP"TRUE"
BODY_TYPE"PLUMBING"
CDS_LIB"mstr_standard";
"B \NAC \NWC"11;
"S \NAC"
BN"10"20;
%"TAP"
"6","(-2875,4700)","2","mstr_standard","I168";
;
HDL_TAP"TRUE"
BODY_TYPE"PLUMBING"
CDS_LIB"mstr_standard";
"B \NAC \NWC"11;
"S \NAC"
BN"17"13;
%"TAP"
"6","(-2875,4600)","2","mstr_standard","I169";
;
HDL_TAP"TRUE"
BODY_TYPE"PLUMBING"
CDS_LIB"mstr_standard";
"B \NAC \NWC"11;
"S \NAC"
BN"15"15;
%"TAP"
"6","(-5600,1250)","0","mstr_standard","I17";
;
HDL_TAP"TRUE"
BODY_TYPE"PLUMBING"
CDS_LIB"mstr_standard";
"B \NAC \NWC"2;
"S \NAC"
BN"3"165;
%"TAP"
"6","(-2875,4650)","2","mstr_standard","I170";
;
HDL_TAP"TRUE"
BODY_TYPE"PLUMBING"
CDS_LIB"mstr_standard";
"B \NAC \NWC"11;
"S \NAC"
BN"16"14;
%"SKX_EXT_B"
"3","(-4200,2600)","0","chpset_lib","I172";
;
CDS_SEC"3"
ROOM"CPU0"
CDS_LOCATION"U5D1"
SEC"3"
SEC_TYPE"BGA1"
CDS_LIB"chpset_lib"
PACK_TYPE"BGA1"
MATERIAL"IC"
PART_NUMBER"TBD"
LOCATION"U5D1";
"DDR0_PAR"
$PN"D53"67;
"DDR0_ODT<0>"
$PN"C50"89;
"DDR0_ODT<1>"
$PN"C48"88;
"DDR0_ODT<2>"
$PN"G50"87;
"DDR0_ODT<3>"
$PN"G48"86;
"DDR0_MA<0>"
$PN"F53"85;
"DDR0_MA<1>"
$PN"F57"84;
"DDR0_MA<2>"
$PN"D57"64;
"DDR0_MA<3>"
$PN"C58"63;
"DDR0_MA<4>"
$PN"G58"62;
"DDR0_MA<5>"
$PN"F59"61;
"DDR0_MA<6>"
$PN"D59"60;
"DDR0_MA<7>"
$PN"G60"59;
"DDR0_MA<8>"
$PN"C60"58;
"DDR0_MA<9>"
$PN"F61"57;
"DDR0_MA<10>"
$PN"J54"56;
"DDR0_MA<11>"
$PN"G62"55;
"DDR0_MA<12>"
$PN"J64"54;
"DDR0_MA<13>"
$PN"J48"53;
"DDR0_MA<14>"
$PN"F51"52;
"DDR0_MA<15>"
$PN"K49"51;
"DDR0_MA<16>"
$PN"D51"50;
"DDR0_MA<17>"
$PN"K47"49;
"DDR0_ECC<0>"
$PN"AC68"168;
"DDR0_ECC<1>"
$PN"AG68"167;
"DDR0_ECC<2>"
$PN"AD65"166;
"DDR0_ECC<3>"
$PN"AF65"165;
"DDR0_ECC<4>"
$PN"AD69"164;
"DDR0_ECC<5>"
$PN"AF69"163;
"DDR0_ECC<6>"
$PN"AC66"162;
"DDR0_ECC<7>"
$PN"AG66"161;
"DDR0_DQS_DP<0>"
$PN"AH85"48;
"DDR0_DQS_DP<1>"
$PN"P85"47;
"DDR0_DQS_DP<2>"
$PN"R80"46;
"DDR0_DQS_DP<3>"
$PN"P75"45;
"DDR0_DQS_DP<4>"
$PN"E40"44;
"DDR0_DQS_DP<5>"
$PN"N36"25;
"DDR0_DQS_DP<6>"
$PN"N30"24;
"DDR0_DQS_DP<7>"
$PN"R24"23;
"DDR0_DQS_DP<8>"
$PN"AF67"22;
"DDR0_DQS_DP<9>"
$PN"AM85"21;
"DDR0_DQS_DP<10>"
$PN"V85"20;
"DDR0_DQS_DP<11>"
$PN"T81"19;
"DDR0_DQS_DP<12>"
$PN"M75"18;
"DDR0_DQS_DP<13>"
$PN"C40"17;
"DDR0_DQS_DP<14>"
$PN"L36"16;
"DDR0_DQS_DP<15>"
$PN"L30"15;
"DDR0_DQS_DP<16>"
$PN"L24"14;
"DDR0_DQS_DP<17>"
$PN"AD67"13;
"DDR0_DQS_DN<0>"
$PN"AJ84"43;
"DDR0_DQS_DN<1>"
$PN"R84"42;
"DDR0_DQS_DN<2>"
$PN"P79"41;
"DDR0_DQS_DN<3>"
$PN"T75"40;
"DDR0_DQS_DN<4>"
$PN"G40"39;
"DDR0_DQS_DN<5>"
$PN"R36"38;
"DDR0_DQS_DN<6>"
$PN"R30"37;
"DDR0_DQS_DN<7>"
$PN"N24"36;
"DDR0_DQS_DN<8>"
$PN"AH67"35;
"DDR0_DQS_DN<9>"
$PN"AL84"34;
"DDR0_DQS_DN<10>"
$PN"U84"33;
"DDR0_DQS_DN<11>"
$PN"U82"32;
"DDR0_DQS_DN<12>"
$PN"K75"31;
"DDR0_DQS_DN<13>"
$PN"A40"30;
"DDR0_DQS_DN<14>"
$PN"J36"29;
"DDR0_DQS_DN<15>"
$PN"J30"28;
"DDR0_DQS_DN<16>"
$PN"J24"27;
"DDR0_DQS_DN<17>"
$PN"AB67"26;
"DDR0_DQ<0>"
$PN"AN86"160;
"DDR0_DQ<1>"
$PN"AN84"159;
"DDR0_DQ<2>"
$PN"AE86"158;
"DDR0_DQ<3>"
$PN"AE84"157;
"DDR0_DQ<4>"
$PN"AR86"170;
"DDR0_DQ<5>"
$PN"AR84"156;
"DDR0_DQ<6>"
$PN"AG86"155;
"DDR0_DQ<7>"
$PN"AG84"154;
"DDR0_DQ<8>"
$PN"W86"153;
"DDR0_DQ<9>"
$PN"W84"152;
"DDR0_DQ<10>"
$PN"L86"143;
"DDR0_DQ<11>"
$PN"L84"142;
"DDR0_DQ<12>"
$PN"AA86"141;
"DDR0_DQ<13>"
$PN"AA84"140;
"DDR0_DQ<14>"
$PN"N86"139;
"DDR0_DQ<15>"
$PN"N84"138;
"DDR0_DQ<16>"
$PN"V81"137;
"DDR0_DQ<17>"
$PN"T79"136;
"DDR0_DQ<18>"
$PN"N82"135;
"DDR0_DQ<19>"
$PN"M81"134;
"DDR0_DQ<20>"
$PN"W80"133;
"DDR0_DQ<21>"
$PN"V79"132;
"DDR0_DQ<22>"
$PN"R82"131;
"DDR0_DQ<23>"
$PN"N80"130;
"DDR0_DQ<24>"
$PN"L76"129;
"DDR0_DQ<25>"
$PN"R76"128;
"DDR0_DQ<26>"
$PN"M73"127;
"DDR0_DQ<27>"
$PN"P73"126;
"DDR0_DQ<28>"
$PN"M77"125;
"DDR0_DQ<29>"
$PN"P77"124;
"DDR0_DQ<30>"
$PN"L74"123;
"DDR0_DQ<31>"
$PN"R74"122;
"DDR0_DQ<32>"
$PN"C42"121;
"DDR0_DQ<33>"
$PN"B41"120;
"DDR0_DQ<34>"
$PN"C38"119;
"DDR0_DQ<35>"
$PN"E38"118;
"DDR0_DQ<36>"
$PN"E42"117;
"DDR0_DQ<37>"
$PN"F41"116;
"DDR0_DQ<38>"
$PN"B39"115;
"DDR0_DQ<39>"
$PN"F39"114;
"DDR0_DQ<40>"
$PN"K37"113;
"DDR0_DQ<41>"
$PN"P37"112;
"DDR0_DQ<42>"
$PN"L34"111;
"DDR0_DQ<43>"
$PN"N34"110;
"DDR0_DQ<44>"
$PN"L38"109;
"DDR0_DQ<45>"
$PN"N38"108;
"DDR0_DQ<46>"
$PN"K35"107;
"DDR0_DQ<47>"
$PN"P35"106;
"DDR0_DQ<48>"
$PN"K31"105;
"DDR0_DQ<49>"
$PN"P31"104;
"DDR0_DQ<50>"
$PN"L28"103;
"DDR0_DQ<51>"
$PN"N28"102;
"DDR0_DQ<52>"
$PN"L32"101;
"DDR0_DQ<53>"
$PN"N32"100;
"DDR0_DQ<54>"
$PN"K29"99;
"DDR0_DQ<55>"
$PN"P29"98;
"DDR0_DQ<56>"
$PN"K25"97;
"DDR0_DQ<57>"
$PN"P25"96;
"DDR0_DQ<58>"
$PN"P23"95;
"DDR0_DQ<59>"
$PN"T23"94;
"DDR0_DQ<60>"
$PN"L26"93;
"DDR0_DQ<61>"
$PN"N26"92;
"DDR0_DQ<62>"
$PN"H23"91;
"DDR0_DQ<63>"
$PN"K23"90;
"DDR0_CS_N<0>"
$PN"G52"83;
"DDR0_CS_N<1>"
$PN"F49"82;
"DDR0_CS_N<2>"
$PN"D47"81;
"DDR0_CS_N<3>"
$PN"F47"80;
"DDR0_CS_N<4>"
$PN"B51"79;
"DDR0_CS_N<5>"
$PN"D49"78;
"DDR0_CS_N<6>"
$PN"F45"77;
"DDR0_CS_N<7>"
$PN"K45"76;
"DDR0_CLK_DP<0>"
$PN"D55"151;
"DDR0_CLK_DP<1>"
$PN"B55"150;
"DDR0_CLK_DP<2>"
$PN"G56"149;
"DDR0_CLK_DP<3>"
$PN"B57"148;
"DDR0_CLK_DN<0>"
$PN"F55"147;
"DDR0_CLK_DN<1>"
$PN"C54"146;
"DDR0_CLK_DN<2>"
$PN"J56"145;
"DDR0_CLK_DN<3>"
$PN"C56"144;
"DDR0_CKE<0>"
$PN"C62"75;
"DDR0_CKE<1>"
$PN"C64"74;
"DDR0_CKE<2>"
$PN"B63"73;
"DDR0_CKE<3>"
$PN"D63"72;
"DDR0_CID<2>"
$PN"G46"169;
"DDR0_BG<0>"
$PN"D61"71;
"DDR0_BG<1>"
$PN"F63"70;
"DDR0_BA<0>"
$PN"C52"69;
"DDR0_BA<1>"
$PN"G54"68;
"DDR0_ALERT_N"
$PN"B61"66;
"DDR0_ACT_N"
$PN"J60"65;
%"TAP"
"6","(-5600,1350)","0","mstr_standard","I18";
;
HDL_TAP"TRUE"
BODY_TYPE"PLUMBING"
CDS_LIB"mstr_standard";
"B \NAC \NWC"2;
"S \NAC"
BN"5"163;
%"TAP"
"6","(-5600,1400)","0","mstr_standard","I19";
;
HDL_TAP"TRUE"
BODY_TYPE"PLUMBING"
CDS_LIB"mstr_standard";
"B \NAC \NWC"2;
"S \NAC"
BN"6"162;
%"TAP"
"6","(-5600,1450)","0","mstr_standard","I20";
;
HDL_TAP"TRUE"
BODY_TYPE"PLUMBING"
CDS_LIB"mstr_standard";
"B \NAC \NWC"2;
"S \NAC"
BN"7"161;
%"TAP"
"6","(-5600,1600)","0","mstr_standard","I21";
;
HDL_TAP"TRUE"
BODY_TYPE"PLUMBING"
CDS_LIB"mstr_standard";
"B \NAC \NWC"1;
"S \NAC"
BN"1"159;
%"TAP"
"6","(-5600,1550)","0","mstr_standard","I22";
;
HDL_TAP"TRUE"
BODY_TYPE"PLUMBING"
CDS_LIB"mstr_standard";
"B \NAC \NWC"1;
"S \NAC"
BN"0"160;
%"TAP"
"6","(-5600,1650)","0","mstr_standard","I23";
;
HDL_TAP"TRUE"
BODY_TYPE"PLUMBING"
CDS_LIB"mstr_standard";
"B \NAC \NWC"1;
"S \NAC"
BN"2"158;
%"TAP"
"6","(-5600,1700)","0","mstr_standard","I24";
;
HDL_TAP"TRUE"
BODY_TYPE"PLUMBING"
CDS_LIB"mstr_standard";
"B \NAC \NWC"1;
"S \NAC"
BN"3"157;
%"TAP"
"6","(-5600,1750)","0","mstr_standard","I25";
;
HDL_TAP"TRUE"
BODY_TYPE"PLUMBING"
CDS_LIB"mstr_standard";
"B \NAC \NWC"1;
"S \NAC"
BN"4"170;
%"TAP"
"6","(-5600,1800)","0","mstr_standard","I26";
;
HDL_TAP"TRUE"
BODY_TYPE"PLUMBING"
CDS_LIB"mstr_standard";
"B \NAC \NWC"1;
"S \NAC"
BN"5"156;
%"TAP"
"6","(-5600,1850)","0","mstr_standard","I27";
;
HDL_TAP"TRUE"
BODY_TYPE"PLUMBING"
CDS_LIB"mstr_standard";
"B \NAC \NWC"1;
"S \NAC"
BN"6"155;
%"TAP"
"6","(-5600,1950)","0","mstr_standard","I28";
;
HDL_TAP"TRUE"
BODY_TYPE"PLUMBING"
CDS_LIB"mstr_standard";
"B \NAC \NWC"1;
"S \NAC"
BN"8"153;
%"TAP"
"6","(-5600,1900)","0","mstr_standard","I29";
;
HDL_TAP"TRUE"
BODY_TYPE"PLUMBING"
CDS_LIB"mstr_standard";
"B \NAC \NWC"1;
"S \NAC"
BN"7"154;
%"TAP"
"6","(-5600,2000)","0","mstr_standard","I31";
;
HDL_TAP"TRUE"
BODY_TYPE"PLUMBING"
CDS_LIB"mstr_standard";
"B \NAC \NWC"1;
"S \NAC"
BN"9"152;
%"TAP"
"6","(-5600,2050)","0","mstr_standard","I32";
;
HDL_TAP"TRUE"
BODY_TYPE"PLUMBING"
CDS_LIB"mstr_standard";
"B \NAC \NWC"1;
"S \NAC"
BN"10"143;
%"TAP"
"6","(-5600,2100)","0","mstr_standard","I33";
;
HDL_TAP"TRUE"
BODY_TYPE"PLUMBING"
CDS_LIB"mstr_standard";
"B \NAC \NWC"1;
"S \NAC"
BN"11"142;
%"TAP"
"6","(-5600,2150)","0","mstr_standard","I34";
;
HDL_TAP"TRUE"
BODY_TYPE"PLUMBING"
CDS_LIB"mstr_standard";
"B \NAC \NWC"1;
"S \NAC"
BN"12"141;
%"TAP"
"6","(-5600,2200)","0","mstr_standard","I35";
;
HDL_TAP"TRUE"
BODY_TYPE"PLUMBING"
CDS_LIB"mstr_standard";
"B \NAC \NWC"1;
"S \NAC"
BN"13"140;
%"TAP"
"6","(-5600,2250)","0","mstr_standard","I36";
;
HDL_TAP"TRUE"
BODY_TYPE"PLUMBING"
CDS_LIB"mstr_standard";
"B \NAC \NWC"1;
"S \NAC"
BN"14"139;
%"TAP"
"6","(-5600,2300)","0","mstr_standard","I37";
;
HDL_TAP"TRUE"
BODY_TYPE"PLUMBING"
CDS_LIB"mstr_standard";
"B \NAC \NWC"1;
"S \NAC"
BN"15"138;
%"TAP"
"6","(-5600,2350)","0","mstr_standard","I38";
;
HDL_TAP"TRUE"
BODY_TYPE"PLUMBING"
CDS_LIB"mstr_standard";
"B \NAC \NWC"1;
"S \NAC"
BN"16"137;
%"TAP"
"6","(-5600,2400)","0","mstr_standard","I39";
;
HDL_TAP"TRUE"
BODY_TYPE"PLUMBING"
CDS_LIB"mstr_standard";
"B \NAC \NWC"1;
"S \NAC"
BN"17"136;
%"TAP"
"6","(-5600,2450)","0","mstr_standard","I40";
;
HDL_TAP"TRUE"
BODY_TYPE"PLUMBING"
CDS_LIB"mstr_standard";
"B \NAC \NWC"1;
"S \NAC"
BN"18"135;
%"TAP"
"6","(-5600,2500)","0","mstr_standard","I41";
;
HDL_TAP"TRUE"
BODY_TYPE"PLUMBING"
CDS_LIB"mstr_standard";
"B \NAC \NWC"1;
"S \NAC"
BN"19"134;
%"TAP"
"6","(-5600,2550)","0","mstr_standard","I42";
;
HDL_TAP"TRUE"
BODY_TYPE"PLUMBING"
CDS_LIB"mstr_standard";
"B \NAC \NWC"1;
"S \NAC"
BN"20"133;
%"TAP"
"6","(-5600,2600)","0","mstr_standard","I43";
;
HDL_TAP"TRUE"
BODY_TYPE"PLUMBING"
CDS_LIB"mstr_standard";
"B \NAC \NWC"1;
"S \NAC"
BN"21"132;
%"TAP"
"6","(-5600,2650)","0","mstr_standard","I44";
;
HDL_TAP"TRUE"
BODY_TYPE"PLUMBING"
CDS_LIB"mstr_standard";
"B \NAC \NWC"1;
"S \NAC"
BN"22"131;
%"TAP"
"6","(-5600,2700)","0","mstr_standard","I45";
;
HDL_TAP"TRUE"
BODY_TYPE"PLUMBING"
CDS_LIB"mstr_standard";
"B \NAC \NWC"1;
"S \NAC"
BN"23"130;
%"TAP"
"6","(-5600,2750)","0","mstr_standard","I46";
;
HDL_TAP"TRUE"
BODY_TYPE"PLUMBING"
CDS_LIB"mstr_standard";
"B \NAC \NWC"1;
"S \NAC"
BN"24"129;
%"TAP"
"6","(-5600,2850)","0","mstr_standard","I47";
;
HDL_TAP"TRUE"
BODY_TYPE"PLUMBING"
CDS_LIB"mstr_standard";
"B \NAC \NWC"1;
"S \NAC"
BN"26"127;
%"TAP"
"6","(-5600,2800)","0","mstr_standard","I48";
;
HDL_TAP"TRUE"
BODY_TYPE"PLUMBING"
CDS_LIB"mstr_standard";
"B \NAC \NWC"1;
"S \NAC"
BN"25"128;
%"TAP"
"6","(-5600,2900)","0","mstr_standard","I49";
;
HDL_TAP"TRUE"
BODY_TYPE"PLUMBING"
CDS_LIB"mstr_standard";
"B \NAC \NWC"1;
"S \NAC"
BN"27"126;
%"TAP"
"6","(-5600,650)","0","mstr_standard","I5";
;
HDL_TAP"TRUE"
BODY_TYPE"PLUMBING"
CDS_LIB"mstr_standard";
"B \NAC \NWC"4;
"S \NAC"
BN"0"147;
%"TAP"
"6","(-5600,2950)","0","mstr_standard","I50";
;
HDL_TAP"TRUE"
BODY_TYPE"PLUMBING"
CDS_LIB"mstr_standard";
"B \NAC \NWC"1;
"S \NAC"
BN"28"125;
%"TAP"
"6","(-5600,3000)","0","mstr_standard","I51";
;
HDL_TAP"TRUE"
BODY_TYPE"PLUMBING"
CDS_LIB"mstr_standard";
"B \NAC \NWC"1;
"S \NAC"
BN"29"124;
%"TAP"
"6","(-5600,3100)","0","mstr_standard","I52";
;
HDL_TAP"TRUE"
BODY_TYPE"PLUMBING"
CDS_LIB"mstr_standard";
"B \NAC \NWC"1;
"S \NAC"
BN"31"122;
%"TAP"
"6","(-5600,3050)","0","mstr_standard","I53";
;
HDL_TAP"TRUE"
BODY_TYPE"PLUMBING"
CDS_LIB"mstr_standard";
"B \NAC \NWC"1;
"S \NAC"
BN"30"123;
%"TAP"
"6","(-5600,3150)","0","mstr_standard","I54";
;
HDL_TAP"TRUE"
BODY_TYPE"PLUMBING"
CDS_LIB"mstr_standard";
"B \NAC \NWC"1;
"S \NAC"
BN"32"121;
%"TAP"
"6","(-5600,3200)","0","mstr_standard","I55";
;
HDL_TAP"TRUE"
BODY_TYPE"PLUMBING"
CDS_LIB"mstr_standard";
"B \NAC \NWC"1;
"S \NAC"
BN"33"120;
%"TAP"
"6","(-5600,3250)","0","mstr_standard","I56";
;
HDL_TAP"TRUE"
BODY_TYPE"PLUMBING"
CDS_LIB"mstr_standard";
"B \NAC \NWC"1;
"S \NAC"
BN"34"119;
%"TAP"
"6","(-5600,3350)","0","mstr_standard","I57";
;
HDL_TAP"TRUE"
BODY_TYPE"PLUMBING"
CDS_LIB"mstr_standard";
"B \NAC \NWC"1;
"S \NAC"
BN"36"117;
%"TAP"
"6","(-5600,3300)","0","mstr_standard","I58";
;
HDL_TAP"TRUE"
BODY_TYPE"PLUMBING"
CDS_LIB"mstr_standard";
"B \NAC \NWC"1;
"S \NAC"
BN"35"118;
%"TAP"
"6","(-5600,3400)","0","mstr_standard","I59";
;
HDL_TAP"TRUE"
BODY_TYPE"PLUMBING"
CDS_LIB"mstr_standard";
"B \NAC \NWC"1;
"S \NAC"
BN"37"116;
%"TAP"
"6","(-5600,700)","0","mstr_standard","I6";
;
HDL_TAP"TRUE"
BODY_TYPE"PLUMBING"
CDS_LIB"mstr_standard";
"B \NAC \NWC"4;
"S \NAC"
BN"1"146;
%"TAP"
"6","(-5600,3450)","0","mstr_standard","I60";
;
HDL_TAP"TRUE"
BODY_TYPE"PLUMBING"
CDS_LIB"mstr_standard";
"B \NAC \NWC"1;
"S \NAC"
BN"38"115;
%"TAP"
"6","(-5600,3500)","0","mstr_standard","I61";
;
HDL_TAP"TRUE"
BODY_TYPE"PLUMBING"
CDS_LIB"mstr_standard";
"B \NAC \NWC"1;
"S \NAC"
BN"39"114;
%"TAP"
"6","(-5600,3550)","0","mstr_standard","I62";
;
HDL_TAP"TRUE"
BODY_TYPE"PLUMBING"
CDS_LIB"mstr_standard";
"B \NAC \NWC"1;
"S \NAC"
BN"40"113;
%"TAP"
"6","(-5600,3600)","0","mstr_standard","I63";
;
HDL_TAP"TRUE"
BODY_TYPE"PLUMBING"
CDS_LIB"mstr_standard";
"B \NAC \NWC"1;
"S \NAC"
BN"41"112;
%"TAP"
"6","(-5600,3650)","0","mstr_standard","I64";
;
HDL_TAP"TRUE"
BODY_TYPE"PLUMBING"
CDS_LIB"mstr_standard";
"B \NAC \NWC"1;
"S \NAC"
BN"42"111;
%"TAP"
"6","(-5600,3700)","0","mstr_standard","I65";
;
HDL_TAP"TRUE"
BODY_TYPE"PLUMBING"
CDS_LIB"mstr_standard";
"B \NAC \NWC"1;
"S \NAC"
BN"43"110;
%"TAP"
"6","(-5600,3750)","0","mstr_standard","I66";
;
HDL_TAP"TRUE"
BODY_TYPE"PLUMBING"
CDS_LIB"mstr_standard";
"B \NAC \NWC"1;
"S \NAC"
BN"44"109;
%"TAP"
"6","(-5600,3800)","0","mstr_standard","I67";
;
HDL_TAP"TRUE"
BODY_TYPE"PLUMBING"
CDS_LIB"mstr_standard";
"B \NAC \NWC"1;
"S \NAC"
BN"45"108;
%"TAP"
"6","(-5600,3850)","0","mstr_standard","I68";
;
HDL_TAP"TRUE"
BODY_TYPE"PLUMBING"
CDS_LIB"mstr_standard";
"B \NAC \NWC"1;
"S \NAC"
BN"46"107;
%"TAP"
"6","(-5600,3900)","0","mstr_standard","I69";
;
HDL_TAP"TRUE"
BODY_TYPE"PLUMBING"
CDS_LIB"mstr_standard";
"B \NAC \NWC"1;
"S \NAC"
BN"47"106;
%"TAP"
"6","(-5600,800)","0","mstr_standard","I7";
;
HDL_TAP"TRUE"
BODY_TYPE"PLUMBING"
CDS_LIB"mstr_standard";
"B \NAC \NWC"4;
"S \NAC"
BN"3"144;
%"TAP"
"6","(-5600,3950)","0","mstr_standard","I70";
;
HDL_TAP"TRUE"
BODY_TYPE"PLUMBING"
CDS_LIB"mstr_standard";
"B \NAC \NWC"1;
"S \NAC"
BN"48"105;
%"TAP"
"6","(-5600,4000)","0","mstr_standard","I71";
;
HDL_TAP"TRUE"
BODY_TYPE"PLUMBING"
CDS_LIB"mstr_standard";
"B \NAC \NWC"1;
"S \NAC"
BN"49"104;
%"TAP"
"6","(-5600,4050)","0","mstr_standard","I73";
;
HDL_TAP"TRUE"
BODY_TYPE"PLUMBING"
CDS_LIB"mstr_standard";
"B \NAC \NWC"1;
"S \NAC"
BN"50"103;
%"TAP"
"6","(-5600,4100)","0","mstr_standard","I74";
;
HDL_TAP"TRUE"
BODY_TYPE"PLUMBING"
CDS_LIB"mstr_standard";
"B \NAC \NWC"1;
"S \NAC"
BN"51"102;
%"TAP"
"6","(-5600,4150)","0","mstr_standard","I75";
;
HDL_TAP"TRUE"
BODY_TYPE"PLUMBING"
CDS_LIB"mstr_standard";
"B \NAC \NWC"1;
"S \NAC"
BN"52"101;
%"TAP"
"6","(-5600,4200)","0","mstr_standard","I76";
;
HDL_TAP"TRUE"
BODY_TYPE"PLUMBING"
CDS_LIB"mstr_standard";
"B \NAC \NWC"1;
"S \NAC"
BN"53"100;
%"TAP"
"6","(-5600,4250)","0","mstr_standard","I77";
;
HDL_TAP"TRUE"
BODY_TYPE"PLUMBING"
CDS_LIB"mstr_standard";
"B \NAC \NWC"1;
"S \NAC"
BN"54"99;
%"TAP"
"6","(-5600,4300)","0","mstr_standard","I78";
;
HDL_TAP"TRUE"
BODY_TYPE"PLUMBING"
CDS_LIB"mstr_standard";
"B \NAC \NWC"1;
"S \NAC"
BN"55"98;
%"TAP"
"6","(-5600,4350)","0","mstr_standard","I79";
;
HDL_TAP"TRUE"
BODY_TYPE"PLUMBING"
CDS_LIB"mstr_standard";
"B \NAC \NWC"1;
"S \NAC"
BN"56"97;
%"TAP"
"6","(-5600,750)","0","mstr_standard","I8";
;
HDL_TAP"TRUE"
BODY_TYPE"PLUMBING"
CDS_LIB"mstr_standard";
"B \NAC \NWC"4;
"S \NAC"
BN"2"145;
%"TAP"
"6","(-5600,4400)","0","mstr_standard","I80";
;
HDL_TAP"TRUE"
BODY_TYPE"PLUMBING"
CDS_LIB"mstr_standard";
"B \NAC \NWC"1;
"S \NAC"
BN"57"96;
%"TAP"
"6","(-5600,4450)","0","mstr_standard","I81";
;
HDL_TAP"TRUE"
BODY_TYPE"PLUMBING"
CDS_LIB"mstr_standard";
"B \NAC \NWC"1;
"S \NAC"
BN"58"95;
%"TAP"
"6","(-5600,4500)","0","mstr_standard","I82";
;
HDL_TAP"TRUE"
BODY_TYPE"PLUMBING"
CDS_LIB"mstr_standard";
"B \NAC \NWC"1;
"S \NAC"
BN"59"94;
%"TAP"
"6","(-5600,4550)","0","mstr_standard","I83";
;
HDL_TAP"TRUE"
BODY_TYPE"PLUMBING"
CDS_LIB"mstr_standard";
"B \NAC \NWC"1;
"S \NAC"
BN"60"93;
%"TAP"
"6","(-5600,4600)","0","mstr_standard","I84";
;
HDL_TAP"TRUE"
BODY_TYPE"PLUMBING"
CDS_LIB"mstr_standard";
"B \NAC \NWC"1;
"S \NAC"
BN"61"92;
%"TAP"
"6","(-5600,4650)","0","mstr_standard","I85";
;
HDL_TAP"TRUE"
BODY_TYPE"PLUMBING"
CDS_LIB"mstr_standard";
"B \NAC \NWC"1;
"S \NAC"
BN"62"91;
%"TAP"
"6","(-5600,4700)","0","mstr_standard","I86";
;
HDL_TAP"TRUE"
BODY_TYPE"PLUMBING"
CDS_LIB"mstr_standard";
"B \NAC \NWC"1;
"S \NAC"
BN"63"90;
%"TAP"
"6","(-2875,800)","2","mstr_standard","I87";
;
HDL_TAP"TRUE"
BODY_TYPE"PLUMBING"
CDS_LIB"mstr_standard";
"B \NAC \NWC"10;
"S \NAC"
BN"1"68;
%"TAP"
"6","(-2875,750)","2","mstr_standard","I88";
;
HDL_TAP"TRUE"
BODY_TYPE"PLUMBING"
CDS_LIB"mstr_standard";
"B \NAC \NWC"10;
"S \NAC"
BN"0"69;
%"TAP"
"6","(-2875,900)","2","mstr_standard","I89";
;
HDL_TAP"TRUE"
BODY_TYPE"PLUMBING"
CDS_LIB"mstr_standard";
"B \NAC \NWC"9;
"S \NAC"
BN"1"70;
%"TAP"
"6","(-5600,900)","0","mstr_standard","I9";
;
HDL_TAP"TRUE"
BODY_TYPE"PLUMBING"
CDS_LIB"mstr_standard";
"B \NAC \NWC"3;
"S \NAC"
BN"1"150;
%"TAP"
"6","(-2875,850)","2","mstr_standard","I90";
;
HDL_TAP"TRUE"
BODY_TYPE"PLUMBING"
CDS_LIB"mstr_standard";
"B \NAC \NWC"9;
"S \NAC"
BN"0"71;
%"TAP"
"6","(-2875,1150)","2","mstr_standard","I91";
;
HDL_TAP"TRUE"
BODY_TYPE"PLUMBING"
CDS_LIB"mstr_standard";
"B \NAC \NWC"7;
"S \NAC"
BN"3"80;
%"TAP"
"6","(-2875,1200)","2","mstr_standard","I92";
;
HDL_TAP"TRUE"
BODY_TYPE"PLUMBING"
CDS_LIB"mstr_standard";
"B \NAC \NWC"7;
"S \NAC"
BN"4"79;
%"TAP"
"6","(-2875,1100)","2","mstr_standard","I93";
;
HDL_TAP"TRUE"
BODY_TYPE"PLUMBING"
CDS_LIB"mstr_standard";
"B \NAC \NWC"7;
"S \NAC"
BN"2"81;
%"TAP"
"6","(-2875,1050)","2","mstr_standard","I94";
;
HDL_TAP"TRUE"
BODY_TYPE"PLUMBING"
CDS_LIB"mstr_standard";
"B \NAC \NWC"7;
"S \NAC"
BN"1"82;
%"TAP"
"6","(-2875,1000)","2","mstr_standard","I95";
;
HDL_TAP"TRUE"
BODY_TYPE"PLUMBING"
CDS_LIB"mstr_standard";
"B \NAC \NWC"7;
"S \NAC"
BN"0"83;
%"TAP"
"6","(-2875,1300)","2","mstr_standard","I96";
;
HDL_TAP"TRUE"
BODY_TYPE"PLUMBING"
CDS_LIB"mstr_standard";
"B \NAC \NWC"7;
"S \NAC"
BN"6"77;
%"TAP"
"6","(-2875,1350)","2","mstr_standard","I97";
;
HDL_TAP"TRUE"
BODY_TYPE"PLUMBING"
CDS_LIB"mstr_standard";
"B \NAC \NWC"7;
"S \NAC"
BN"7"76;
%"TAP"
"6","(-2875,1250)","2","mstr_standard","I98";
;
HDL_TAP"TRUE"
BODY_TYPE"PLUMBING"
CDS_LIB"mstr_standard";
"B \NAC \NWC"7;
"S \NAC"
BN"5"78;
%"TAP"
"6","(-2875,1450)","2","mstr_standard","I99";
;
HDL_TAP"TRUE"
BODY_TYPE"PLUMBING"
CDS_LIB"mstr_standard";
"B \NAC \NWC"5;
"S \NAC"
BN"0"89;
END.
